(kicad_pcb
	(version 20260206)
	(generator "pcbnew")
	(generator_version "10.0")
	(general
		(thickness 1.6)
		(legacy_teardrops no)
	)
	(paper "A4")
	(title_block
		(title "01162023_DA0F0TEBIF0_F0T_Expander_BD_F_brd_V02_OCP.brd")
		(comment 1 "Grand Teton / footprints 2252-2257 of 9728")
	)
	(layers
		(0 "F.Cu" signal "TOP")
		(4 "In1.Cu" signal "GND")
		(6 "In2.Cu" signal "VCC")
		(8 "In3.Cu" signal "VCC1")
		(10 "In4.Cu" signal "GND1")
		(12 "In5.Cu" signal "IN1")
		(14 "In6.Cu" signal "GND2")
		(16 "In7.Cu" signal "IN2")
		(18 "In8.Cu" signal "GND3")
		(20 "In9.Cu" signal "IN3")
		(22 "In10.Cu" signal "GND4")
		(24 "In11.Cu" signal "IN4")
		(26 "In12.Cu" signal "GND5")
		(28 "In13.Cu" signal "IN5")
		(30 "In14.Cu" signal "GND6")
		(32 "In15.Cu" signal "IN6")
		(34 "In16.Cu" signal "GND7")
		(2 "B.Cu" signal "BOTTOM")
		(9 "F.Adhes" user "F.Adhesive")
		(11 "B.Adhes" user "B.Adhesive")
		(13 "F.Paste" user "Package Geometry/Pastemask Top")
		(15 "B.Paste" user "Package Geometry/Pastemask Bottom")
		(5 "F.SilkS" user "Ref Des/Silkscreen Top")
		(7 "B.SilkS" user "Ref Des/Silkscreen Bottom")
		(1 "F.Mask" user "Board Geometry/Soldermask Top")
		(3 "B.Mask" user "Board Geometry/Soldermask Bottom")
		(17 "Dwgs.User" user "User.Drawings")
		(19 "Cmts.User" user "User.Comments")
		(21 "Eco1.User" user "User.Eco1")
		(23 "Eco2.User" user "User.Eco2")
		(25 "Edge.Cuts" user "Board Geometry/Outline")
		(27 "Margin" user)
		(31 "F.CrtYd" user "Package Geometry/Place Bound Top")
		(29 "B.CrtYd" user "Package Geometry/Place Bound Bottom")
		(35 "F.Fab" user "Ref Des/Assembly Top")
		(33 "B.Fab" user "Ref Des/Assembly Bottom")
	)
	(footprint ""
		(layer "F.Cu")
		(at 325.287386 -96.811592 90)
		(property "Reference" "R743"
			(at 0 0 90)
			(layer "F.SilkS")
			(hide yes)
			(effects
				(font
					(size 1.27 1.27)
				)
			)
		)
		(property "Value" ""
			(at 0 0 90)
			(layer "F.Fab")
			(effects
				(font
					(size 1.27 1.27)
				)
			)
		)
		(duplicate_pad_numbers_are_jumpers no)
		(fp_line
			(start 0.7874 -0.4064)
			(end 0.7874 0.4064)
			(stroke
				(width 0.1524)
				(type default)
			)
			(layer "F.SilkS")
		)
		(fp_line
			(start -0.7874 -0.4064)
			(end 0.7874 -0.4064)
			(stroke
				(width 0.1524)
				(type default)
			)
			(layer "F.SilkS")
		)
		(fp_line
			(start 0.7874 0.4064)
			(end -0.7874 0.4064)
			(stroke
				(width 0.1524)
				(type default)
			)
			(layer "F.SilkS")
		)
		(fp_line
			(start -0.7874 0.4064)
			(end -0.7874 -0.4064)
			(stroke
				(width 0.1524)
				(type default)
			)
			(layer "F.SilkS")
		)
		(fp_line
			(start -0.12065 -0.305054)
			(end -0.12065 -0.2794)
			(stroke
				(width 0.1)
				(type default)
			)
			(layer "F.Fab")
		)
		(fp_line
			(start -0.67945 -0.305054)
			(end -0.12065 -0.305054)
			(stroke
				(width 0.1)
				(type default)
			)
			(layer "F.Fab")
		)
		(fp_line
			(start 0.67945 -0.3048)
			(end 0.67945 0.3048)
			(stroke
				(width 0.1)
				(type default)
			)
			(layer "F.Fab")
		)
		(fp_line
			(start 0.12065 -0.3048)
			(end 0.67945 -0.3048)
			(stroke
				(width 0.1)
				(type default)
			)
			(layer "F.Fab")
		)
		(fp_line
			(start 0.12065 -0.2794)
			(end 0.12065 -0.3048)
			(stroke
				(width 0.1)
				(type default)
			)
			(layer "F.Fab")
		)
		(fp_line
			(start -0.12065 -0.2794)
			(end 0.12065 -0.2794)
			(stroke
				(width 0.1)
				(type default)
			)
			(layer "F.Fab")
		)
		(fp_line
			(start 0.120396 0.2794)
			(end -0.12065 0.2794)
			(stroke
				(width 0.1)
				(type default)
			)
			(layer "F.Fab")
		)
		(fp_line
			(start -0.12065 0.2794)
			(end -0.12065 0.3048)
			(stroke
				(width 0.1)
				(type default)
			)
			(layer "F.Fab")
		)
		(fp_line
			(start 0.67945 0.3048)
			(end 0.120396 0.3048)
			(stroke
				(width 0.1)
				(type default)
			)
			(layer "F.Fab")
		)
		(fp_line
			(start 0.120396 0.3048)
			(end 0.120396 0.2794)
			(stroke
				(width 0.1)
				(type default)
			)
			(layer "F.Fab")
		)
		(fp_line
			(start -0.12065 0.3048)
			(end -0.67945 0.3048)
			(stroke
				(width 0.1)
				(type default)
			)
			(layer "F.Fab")
		)
		(fp_line
			(start -0.67945 0.3048)
			(end -0.67945 -0.305054)
			(stroke
				(width 0.1)
				(type default)
			)
			(layer "F.Fab")
		)
		(pad "1" smd circle
			(at -0.40005 0 90)
			(size 0 0)
			(layers "F.Cu" "F.Mask" "F.Paste")
			(net "SMB_BIC_I2C6_MUX_NIC_ADC_R_SDA")
		)
		(pad "2" smd circle
			(at 0.40005 0 90)
			(size 0 0)
			(layers "F.Cu" "F.Mask" "F.Paste")
			(net "SMB_NIC5_ADC_SDA")
		)
	)
	(footprint ""
		(layer "F.Cu")
		(at 103.611426 -71.458074 -90)
		(property "Reference" "PD89"
			(at 4.300474 -2.663444 90)
			(unlocked yes)
			(layer "F.SilkS")
			(effects
				(font
					(size 0.7874 0.5842)
					(thickness 0.1524)
				)
				(justify left)
			)
		)
		(property "Value" ""
			(at 0 0 270)
			(layer "F.Fab")
			(effects
				(font
					(size 1.27 1.27)
				)
			)
		)
		(duplicate_pad_numbers_are_jumpers no)
		(fp_line
			(start -3.656584 1.970024)
			(end 4.240784 1.970024)
			(stroke
				(width 0.1524)
				(type default)
			)
			(layer "F.SilkS")
		)
		(fp_line
			(start 4.240784 1.970024)
			(end 4.240784 -1.970024)
			(stroke
				(width 0.1524)
				(type default)
			)
			(layer "F.SilkS")
		)
		(fp_line
			(start -3.656584 -1.970024)
			(end -3.656584 1.970024)
			(stroke
				(width 0.1524)
				(type default)
			)
			(layer "F.SilkS")
		)
		(fp_line
			(start 4.240784 -1.970024)
			(end -3.656584 -1.970024)
			(stroke
				(width 0.1524)
				(type default)
			)
			(layer "F.SilkS")
		)
		(fp_poly
			(pts
				(xy 3.580384 1.970024) (xy 3.580384 -1.970024) (xy 4.240784 -1.970024) (xy 4.240784 1.970024)
			)
			(stroke
				(width 0)
				(type default)
			)
			(fill yes)
			(layer "F.SilkS")
		)
		(fp_line
			(start -2.3749 1.970024)
			(end 2.3749 1.970024)
			(stroke
				(width 0.1)
				(type default)
			)
			(layer "F.Fab")
		)
		(fp_line
			(start 2.3749 1.970024)
			(end 2.3749 -1.970024)
			(stroke
				(width 0.1)
				(type default)
			)
			(layer "F.Fab")
		)
		(fp_line
			(start -2.3749 -1.970024)
			(end -2.3749 1.970024)
			(stroke
				(width 0.1)
				(type default)
			)
			(layer "F.Fab")
		)
		(fp_line
			(start 2.3749 -1.970024)
			(end -2.3749 -1.970024)
			(stroke
				(width 0.1)
				(type default)
			)
			(layer "F.Fab")
		)
		(fp_text user "+"
			(at -4.9784 -0.23495 270)
			(unlocked yes)
			(layer "F.Fab")
			(effects
				(font
					(size 1.905 1.4224)
					(thickness 0.1524)
				)
				(justify left)
			)
		)
		(fp_text user "-"
			(at 4.1656 -0.23495 270)
			(unlocked yes)
			(layer "F.Fab")
			(effects
				(font
					(size 1.905 1.4224)
					(thickness 0.1524)
				)
				(justify left)
			)
		)
		(pad "A" smd rect
			(at -2.450084 0 270)
			(size 2.159 2.2606)
			(layers "F.Cu" "F.Mask" "F.Paste")
			(net "GND")
		)
		(pad "C" smd rect
			(at 2.450084 0 270)
			(size 2.159 2.2606)
			(layers "F.Cu" "F.Mask" "F.Paste")
			(net "P12V_AUX")
		)
	)
	(footprint ""
		(layer "F.Cu")
		(at 194.343782 -42.84091)
		(property "Reference" "R571"
			(at 0 0 0)
			(layer "F.SilkS")
			(hide yes)
			(effects
				(font
					(size 1.27 1.27)
				)
			)
		)
		(property "Value" ""
			(at 0 0 0)
			(layer "F.Fab")
			(effects
				(font
					(size 1.27 1.27)
				)
			)
		)
		(duplicate_pad_numbers_are_jumpers no)
		(fp_line
			(start -0.7874 -0.4064)
			(end 0.7874 -0.4064)
			(stroke
				(width 0.1524)
				(type default)
			)
			(layer "F.SilkS")
		)
		(fp_line
			(start -0.7874 0.4064)
			(end -0.7874 -0.4064)
			(stroke
				(width 0.1524)
				(type default)
			)
			(layer "F.SilkS")
		)
		(fp_line
			(start 0.7874 -0.4064)
			(end 0.7874 0.4064)
			(stroke
				(width 0.1524)
				(type default)
			)
			(layer "F.SilkS")
		)
		(fp_line
			(start 0.7874 0.4064)
			(end -0.7874 0.4064)
			(stroke
				(width 0.1524)
				(type default)
			)
			(layer "F.SilkS")
		)
		(fp_line
			(start -0.67945 -0.305054)
			(end -0.12065 -0.305054)
			(stroke
				(width 0.1)
				(type default)
			)
			(layer "F.Fab")
		)
		(fp_line
			(start -0.67945 0.3048)
			(end -0.67945 -0.305054)
			(stroke
				(width 0.1)
				(type default)
			)
			(layer "F.Fab")
		)
		(fp_line
			(start -0.12065 -0.305054)
			(end -0.12065 -0.2794)
			(stroke
				(width 0.1)
				(type default)
			)
			(layer "F.Fab")
		)
		(fp_line
			(start -0.12065 -0.2794)
			(end 0.12065 -0.2794)
			(stroke
				(width 0.1)
				(type default)
			)
			(layer "F.Fab")
		)
		(fp_line
			(start -0.12065 0.2794)
			(end -0.12065 0.3048)
			(stroke
				(width 0.1)
				(type default)
			)
			(layer "F.Fab")
		)
		(fp_line
			(start -0.12065 0.3048)
			(end -0.67945 0.3048)
			(stroke
				(width 0.1)
				(type default)
			)
			(layer "F.Fab")
		)
		(fp_line
			(start 0.120396 0.2794)
			(end -0.12065 0.2794)
			(stroke
				(width 0.1)
				(type default)
			)
			(layer "F.Fab")
		)
		(fp_line
			(start 0.120396 0.3048)
			(end 0.120396 0.2794)
			(stroke
				(width 0.1)
				(type default)
			)
			(layer "F.Fab")
		)
		(fp_line
			(start 0.12065 -0.3048)
			(end 0.67945 -0.3048)
			(stroke
				(width 0.1)
				(type default)
			)
			(layer "F.Fab")
		)
		(fp_line
			(start 0.12065 -0.2794)
			(end 0.12065 -0.3048)
			(stroke
				(width 0.1)
				(type default)
			)
			(layer "F.Fab")
		)
		(fp_line
			(start 0.67945 -0.3048)
			(end 0.67945 0.3048)
			(stroke
				(width 0.1)
				(type default)
			)
			(layer "F.Fab")
		)
		(fp_line
			(start 0.67945 0.3048)
			(end 0.120396 0.3048)
			(stroke
				(width 0.1)
				(type default)
			)
			(layer "F.Fab")
		)
		(pad "1" smd circle
			(at -0.40005 0)
			(size 0 0)
			(layers "F.Cu" "F.Mask" "F.Paste")
			(net "SSD6_ADC_A1")
		)
		(pad "2" smd circle
			(at 0.40005 0)
			(size 0 0)
			(layers "F.Cu" "F.Mask" "F.Paste")
			(net "P3V3_AUX")
		)
	)
	(footprint ""
		(layer "F.Cu")
		(at 169.759884 -195.868798)
		(property "Reference" "R3289"
			(at 0 0 0)
			(layer "F.SilkS")
			(hide yes)
			(effects
				(font
					(size 1.27 1.27)
				)
			)
		)
		(property "Value" ""
			(at 0 0 0)
			(layer "F.Fab")
			(effects
				(font
					(size 1.27 1.27)
				)
			)
		)
		(duplicate_pad_numbers_are_jumpers no)
		(fp_line
			(start -0.7874 -0.4064)
			(end 0.7874 -0.4064)
			(stroke
				(width 0.1524)
				(type default)
			)
			(layer "F.SilkS")
		)
		(fp_line
			(start -0.7874 0.4064)
			(end -0.7874 -0.4064)
			(stroke
				(width 0.1524)
				(type default)
			)
			(layer "F.SilkS")
		)
		(fp_line
			(start 0.7874 -0.4064)
			(end 0.7874 0.4064)
			(stroke
				(width 0.1524)
				(type default)
			)
			(layer "F.SilkS")
		)
		(fp_line
			(start 0.7874 0.4064)
			(end -0.7874 0.4064)
			(stroke
				(width 0.1524)
				(type default)
			)
			(layer "F.SilkS")
		)
		(fp_line
			(start -0.67945 -0.305054)
			(end -0.12065 -0.305054)
			(stroke
				(width 0.1)
				(type default)
			)
			(layer "F.Fab")
		)
		(fp_line
			(start -0.67945 0.3048)
			(end -0.67945 -0.305054)
			(stroke
				(width 0.1)
				(type default)
			)
			(layer "F.Fab")
		)
		(fp_line
			(start -0.12065 -0.305054)
			(end -0.12065 -0.2794)
			(stroke
				(width 0.1)
				(type default)
			)
			(layer "F.Fab")
		)
		(fp_line
			(start -0.12065 -0.2794)
			(end 0.12065 -0.2794)
			(stroke
				(width 0.1)
				(type default)
			)
			(layer "F.Fab")
		)
		(fp_line
			(start -0.12065 0.2794)
			(end -0.12065 0.3048)
			(stroke
				(width 0.1)
				(type default)
			)
			(layer "F.Fab")
		)
		(fp_line
			(start -0.12065 0.3048)
			(end -0.67945 0.3048)
			(stroke
				(width 0.1)
				(type default)
			)
			(layer "F.Fab")
		)
		(fp_line
			(start 0.120396 0.2794)
			(end -0.12065 0.2794)
			(stroke
				(width 0.1)
				(type default)
			)
			(layer "F.Fab")
		)
		(fp_line
			(start 0.120396 0.3048)
			(end 0.120396 0.2794)
			(stroke
				(width 0.1)
				(type default)
			)
			(layer "F.Fab")
		)
		(fp_line
			(start 0.12065 -0.3048)
			(end 0.67945 -0.3048)
			(stroke
				(width 0.1)
				(type default)
			)
			(layer "F.Fab")
		)
		(fp_line
			(start 0.12065 -0.2794)
			(end 0.12065 -0.3048)
			(stroke
				(width 0.1)
				(type default)
			)
			(layer "F.Fab")
		)
		(fp_line
			(start 0.67945 -0.3048)
			(end 0.67945 0.3048)
			(stroke
				(width 0.1)
				(type default)
			)
			(layer "F.Fab")
		)
		(fp_line
			(start 0.67945 0.3048)
			(end 0.120396 0.3048)
			(stroke
				(width 0.1)
				(type default)
			)
			(layer "F.Fab")
		)
		(pad "1" smd circle
			(at -0.40005 0)
			(size 0 0)
			(layers "F.Cu" "F.Mask" "F.Paste")
			(net "SPI_BIC1_MOSI_LS01_R")
		)
		(pad "2" smd circle
			(at 0.40005 0)
			(size 0 0)
			(layers "F.Cu" "F.Mask" "F.Paste")
			(net "SPI_BIC1_MOSI_LS01")
		)
	)
	(footprint ""
		(layer "F.Cu")
		(at 136.587738 -25.342342 -90)
		(property "Reference" "R423"
			(at 0 0 270)
			(layer "F.SilkS")
			(hide yes)
			(effects
				(font
					(size 1.27 1.27)
				)
			)
		)
		(property "Value" ""
			(at 0 0 270)
			(layer "F.Fab")
			(effects
				(font
					(size 1.27 1.27)
				)
			)
		)
		(duplicate_pad_numbers_are_jumpers no)
		(fp_line
			(start -0.7874 0.4064)
			(end -0.7874 -0.4064)
			(stroke
				(width 0.1524)
				(type default)
			)
			(layer "F.SilkS")
		)
		(fp_line
			(start 0.7874 0.4064)
			(end -0.7874 0.4064)
			(stroke
				(width 0.1524)
				(type default)
			)
			(layer "F.SilkS")
		)
		(fp_line
			(start -0.7874 -0.4064)
			(end 0.7874 -0.4064)
			(stroke
				(width 0.1524)
				(type default)
			)
			(layer "F.SilkS")
		)
		(fp_line
			(start 0.7874 -0.4064)
			(end 0.7874 0.4064)
			(stroke
				(width 0.1524)
				(type default)
			)
			(layer "F.SilkS")
		)
		(fp_line
			(start -0.67945 0.3048)
			(end -0.67945 -0.305054)
			(stroke
				(width 0.1)
				(type default)
			)
			(layer "F.Fab")
		)
		(fp_line
			(start -0.12065 0.3048)
			(end -0.67945 0.3048)
			(stroke
				(width 0.1)
				(type default)
			)
			(layer "F.Fab")
		)
		(fp_line
			(start 0.120396 0.3048)
			(end 0.120396 0.2794)
			(stroke
				(width 0.1)
				(type default)
			)
			(layer "F.Fab")
		)
		(fp_line
			(start 0.67945 0.3048)
			(end 0.120396 0.3048)
			(stroke
				(width 0.1)
				(type default)
			)
			(layer "F.Fab")
		)
		(fp_line
			(start -0.12065 0.2794)
			(end -0.12065 0.3048)
			(stroke
				(width 0.1)
				(type default)
			)
			(layer "F.Fab")
		)
		(fp_line
			(start 0.120396 0.2794)
			(end -0.12065 0.2794)
			(stroke
				(width 0.1)
				(type default)
			)
			(layer "F.Fab")
		)
		(fp_line
			(start -0.12065 -0.2794)
			(end 0.12065 -0.2794)
			(stroke
				(width 0.1)
				(type default)
			)
			(layer "F.Fab")
		)
		(fp_line
			(start 0.12065 -0.2794)
			(end 0.12065 -0.3048)
			(stroke
				(width 0.1)
				(type default)
			)
			(layer "F.Fab")
		)
		(fp_line
			(start 0.12065 -0.3048)
			(end 0.67945 -0.3048)
			(stroke
				(width 0.1)
				(type default)
			)
			(layer "F.Fab")
		)
		(fp_line
			(start 0.67945 -0.3048)
			(end 0.67945 0.3048)
			(stroke
				(width 0.1)
				(type default)
			)
			(layer "F.Fab")
		)
		(fp_line
			(start -0.67945 -0.305054)
			(end -0.12065 -0.305054)
			(stroke
				(width 0.1)
				(type default)
			)
			(layer "F.Fab")
		)
		(fp_line
			(start -0.12065 -0.305054)
			(end -0.12065 -0.2794)
			(stroke
				(width 0.1)
				(type default)
			)
			(layer "F.Fab")
		)
		(pad "1" smd circle
			(at -0.40005 0 270)
			(size 0 0)
			(layers "F.Cu" "F.Mask" "F.Paste")
			(net "GND")
		)
		(pad "2" smd circle
			(at 0.40005 0 270)
			(size 0 0)
			(layers "F.Cu" "F.Mask" "F.Paste")
			(net "DUALPORT_N_SSD4")
		)
	)
	(footprint ""
		(layer "F.Cu")
		(at 365.506 -206.883 180)
		(property "Reference" "R4628"
			(at 0 0 180)
			(layer "F.SilkS")
			(hide yes)
			(effects
				(font
					(size 1.27 1.27)
				)
			)
		)
		(property "Value" ""
			(at 0 0 180)
			(layer "F.Fab")
			(effects
				(font
					(size 1.27 1.27)
				)
			)
		)
		(duplicate_pad_numbers_are_jumpers no)
		(fp_line
			(start 0.7874 0.4064)
			(end -0.7874 0.4064)
			(stroke
				(width 0.1524)
				(type default)
			)
			(layer "F.SilkS")
		)
		(fp_line
			(start 0.7874 -0.4064)
			(end 0.7874 0.4064)
			(stroke
				(width 0.1524)
				(type default)
			)
			(layer "F.SilkS")
		)
		(fp_line
			(start -0.7874 0.4064)
			(end -0.7874 -0.4064)
			(stroke
				(width 0.1524)
				(type default)
			)
			(layer "F.SilkS")
		)
		(fp_line
			(start -0.7874 -0.4064)
			(end 0.7874 -0.4064)
			(stroke
				(width 0.1524)
				(type default)
			)
			(layer "F.SilkS")
		)
		(fp_line
			(start 0.67945 0.3048)
			(end 0.120396 0.3048)
			(stroke
				(width 0.1)
				(type default)
			)
			(layer "F.Fab")
		)
		(fp_line
			(start 0.67945 -0.3048)
			(end 0.67945 0.3048)
			(stroke
				(width 0.1)
				(type default)
			)
			(layer "F.Fab")
		)
		(fp_line
			(start 0.12065 -0.2794)
			(end 0.12065 -0.3048)
			(stroke
				(width 0.1)
				(type default)
			)
			(layer "F.Fab")
		)
		(fp_line
			(start 0.12065 -0.3048)
			(end 0.67945 -0.3048)
			(stroke
				(width 0.1)
				(type default)
			)
			(layer "F.Fab")
		)
		(fp_line
			(start 0.120396 0.3048)
			(end 0.120396 0.2794)
			(stroke
				(width 0.1)
				(type default)
			)
			(layer "F.Fab")
		)
		(fp_line
			(start 0.120396 0.2794)
			(end -0.12065 0.2794)
			(stroke
				(width 0.1)
				(type default)
			)
			(layer "F.Fab")
		)
		(fp_line
			(start -0.12065 0.3048)
			(end -0.67945 0.3048)
			(stroke
				(width 0.1)
				(type default)
			)
			(layer "F.Fab")
		)
		(fp_line
			(start -0.12065 0.2794)
			(end -0.12065 0.3048)
			(stroke
				(width 0.1)
				(type default)
			)
			(layer "F.Fab")
		)
		(fp_line
			(start -0.12065 -0.2794)
			(end 0.12065 -0.2794)
			(stroke
				(width 0.1)
				(type default)
			)
			(layer "F.Fab")
		)
		(fp_line
			(start -0.12065 -0.305054)
			(end -0.12065 -0.2794)
			(stroke
				(width 0.1)
				(type default)
			)
			(layer "F.Fab")
		)
		(fp_line
			(start -0.67945 0.3048)
			(end -0.67945 -0.305054)
			(stroke
				(width 0.1)
				(type default)
			)
			(layer "F.Fab")
		)
		(fp_line
			(start -0.67945 -0.305054)
			(end -0.12065 -0.305054)
			(stroke
				(width 0.1)
				(type default)
			)
			(layer "F.Fab")
		)
		(pad "1" smd circle
			(at -0.40005 0 180)
			(size 0 0)
			(layers "F.Cu" "F.Mask" "F.Paste")
			(net "SSD1_PEX_PWR_EN")
		)
		(pad "2" smd circle
			(at 0.40005 0 180)
			(size 0 0)
			(layers "F.Cu" "F.Mask" "F.Paste")
			(net "SSD1_PEX_PWR_EN_R")
		)
	)
)
